(kicad_pcb
	(version 20241229)
	(generator "pcbnew")
	(generator_version "9.0")
	(general
		(thickness 1.599998)
		(legacy_teardrops no)
	)
	(paper "A4")
	(title_block
		(title "Artix - Datacenter Secure Control Module (DC-SCM)")
		(date "2024-11-06")
		(rev "1.1.3")
		(comment 9 "footprints 21-24 of 544")
	)
	(layers
		(0 "F.Cu" signal)
		(4 "In1.Cu" signal)
		(6 "In2.Cu" signal)
		(8 "In3.Cu" signal)
		(10 "In4.Cu" signal)
		(12 "In5.Cu" signal)
		(14 "In6.Cu" signal)
		(2 "B.Cu" signal)
		(9 "F.Adhes" user "F.Adhesive")
		(11 "B.Adhes" user "B.Adhesive")
		(13 "F.Paste" user)
		(15 "B.Paste" user)
		(5 "F.SilkS" user "F.Silkscreen")
		(7 "B.SilkS" user "B.Silkscreen")
		(1 "F.Mask" user)
		(3 "B.Mask" user)
		(17 "Dwgs.User" user "User.Drawings")
		(19 "Cmts.User" user "User.Comments")
		(21 "Eco1.User" user "User.Eco1")
		(23 "Eco2.User" user "User.Eco2")
		(25 "Edge.Cuts" user)
		(27 "Margin" user)
		(31 "F.CrtYd" user "F.Courtyard")
		(29 "B.CrtYd" user "B.Courtyard")
		(35 "F.Fab" user)
		(33 "B.Fab" user)
	)
	(footprint "antmicro-footprints:VSON-10-1EP_3x3mm"
		(layer "F.Cu")
		(at 102.0755 159.785)
		(property "Reference" "U8"
			(at 0.7245 -2.185 0)
			(layer "F.SilkS")
			(effects
				(font
					(size 0.7 0.7)
					(thickness 0.15)
				)
			)
		)
		(property "Value" "TPS51200DRCT"
			(at -0.3 2.9 0)
			(layer "F.Fab")
			(effects
				(font
					(size 1 1)
					(thickness 0.15)
				)
			)
		)
		(property "Datasheet" "https://www.ti.com/lit/ds/symlink/tps51200.pdf?ts=1685420125657"
			(at 0 0 0)
			(layer "F.Fab")
			(hide yes)
			(effects
				(font
					(size 1.27 1.27)
					(thickness 0.15)
				)
			)
		)
		(property "Description" "Fixed LDO Voltage Regulator, 2.375 V to 3.5 V, 0.8 V Dropout, 1.25 V / 3 A out, VSON-10"
			(at 0 0 0)
			(layer "F.Fab")
			(hide yes)
			(effects
				(font
					(size 1.27 1.27)
					(thickness 0.15)
				)
			)
		)
		(property "Author" "Antmicro"
			(at 0 0 0)
			(layer "F.Fab")
			(hide yes)
			(effects
				(font
					(size 1 1)
					(thickness 0.15)
				)
			)
		)
		(property "License" "Apache-2.0"
			(at 0 0 0)
			(layer "F.Fab")
			(hide yes)
			(effects
				(font
					(size 1 1)
					(thickness 0.15)
				)
			)
		)
		(property "MPN" "TPS51200DRCT"
			(at 0 0 0)
			(layer "F.Fab")
			(hide yes)
			(effects
				(font
					(size 1 1)
					(thickness 0.15)
				)
			)
		)
		(property "Manufacturer" "Texas Instruments"
			(at 0 0 0)
			(layer "F.Fab")
			(hide yes)
			(effects
				(font
					(size 1 1)
					(thickness 0.15)
				)
			)
		)
		(property "VSD_class" "TPS51200"
			(at 0 0 0)
			(layer "F.Fab")
			(hide yes)
			(effects
				(font
					(size 1 1)
					(thickness 0.15)
				)
			)
		)
		(property ki_fp_filters "*VSON?10?1EP?3x3mm?P0.5mm*")
		(sheetname "/DDR3/")
		(sheetfile "ddr3.kicad_sch")
		(attr smd)
		(fp_line
			(start -1.5 1.598)
			(end 1.499 1.598)
			(stroke
				(width 0.15)
				(type solid)
			)
			(layer "F.SilkS")
		)
		(fp_line
			(start 0 -1.621)
			(end 1.499 -1.621)
			(stroke
				(width 0.15)
				(type solid)
			)
			(layer "F.SilkS")
		)
		(fp_line
			(start -1.97 1.215)
			(end -1.97 -1.24)
			(stroke
				(width 0.05)
				(type solid)
			)
			(layer "F.CrtYd")
		)
		(fp_line
			(start -1.65 -1.65)
			(end -1.65 -1.24)
			(stroke
				(width 0.05)
				(type solid)
			)
			(layer "F.CrtYd")
		)
		(fp_line
			(start -1.65 -1.24)
			(end -1.97 -1.24)
			(stroke
				(width 0.05)
				(type solid)
			)
			(layer "F.CrtYd")
		)
		(fp_line
			(start -1.65 1.215)
			(end -1.97 1.215)
			(stroke
				(width 0.05)
				(type solid)
			)
			(layer "F.CrtYd")
		)
		(fp_line
			(start -1.65 1.215)
			(end -1.65 1.625)
			(stroke
				(width 0.05)
				(type solid)
			)
			(layer "F.CrtYd")
		)
		(fp_line
			(start -1.65 1.625)
			(end 1.65 1.625)
			(stroke
				(width 0.05)
				(type solid)
			)
			(layer "F.CrtYd")
		)
		(fp_line
			(start 1.65 -1.65)
			(end -1.65 -1.65)
			(stroke
				(width 0.05)
				(type solid)
			)
			(layer "F.CrtYd")
		)
		(fp_line
			(start 1.65 -1.24)
			(end 1.65 -1.65)
			(stroke
				(width 0.05)
				(type solid)
			)
			(layer "F.CrtYd")
		)
		(fp_line
			(start 1.65 -1.24)
			(end 1.97 -1.24)
			(stroke
				(width 0.05)
				(type solid)
			)
			(layer "F.CrtYd")
		)
		(fp_line
			(start 1.65 1.215)
			(end 1.97 1.215)
			(stroke
				(width 0.05)
				(type solid)
			)
			(layer "F.CrtYd")
		)
		(fp_line
			(start 1.65 1.625)
			(end 1.65 1.215)
			(stroke
				(width 0.05)
				(type solid)
			)
			(layer "F.CrtYd")
		)
		(fp_line
			(start 1.97 -1.24)
			(end 1.97 1.215)
			(stroke
				(width 0.05)
				(type solid)
			)
			(layer "F.CrtYd")
		)
		(fp_line
			(start -1.5 -0.76)
			(end -0.75 -1.51)
			(stroke
				(width 0.15)
				(type solid)
			)
			(layer "F.Fab")
		)
		(fp_line
			(start -1.5 1.489)
			(end -1.5 -0.76)
			(stroke
				(width 0.15)
				(type solid)
			)
			(layer "F.Fab")
		)
		(fp_line
			(start -0.75 -1.51)
			(end 1.499 -1.51)
			(stroke
				(width 0.15)
				(type solid)
			)
			(layer "F.Fab")
		)
		(fp_line
			(start 1.499 -1.51)
			(end 1.499 1.489)
			(stroke
				(width 0.15)
				(type solid)
			)
			(layer "F.Fab")
		)
		(fp_line
			(start 1.499 1.489)
			(end -1.5 1.489)
			(stroke
				(width 0.15)
				(type solid)
			)
			(layer "F.Fab")
		)
		(fp_text user "."
			(at -2.05 -1.65 0)
			(layer "F.SilkS")
			(effects
				(font
					(size 1 1)
					(thickness 0.15)
				)
			)
		)
		(fp_text user "${REFERENCE}"
			(at 0.2 -0.2 0)
			(layer "F.Fab")
			(effects
				(font
					(size 0.75 0.75)
					(thickness 0.11)
				)
			)
		)
		(pad "" smd roundrect
			(at -0.3 -0.51)
			(size 0.48 0.81)
			(layers "F.Paste")
			(roundrect_rratio 0.25)
		)
		(pad "" smd roundrect
			(at -0.3 0.488)
			(size 0.48 0.81)
			(layers "F.Paste")
			(roundrect_rratio 0.25)
		)
		(pad "" smd roundrect
			(at 0.299 -0.51)
			(size 0.48 0.81)
			(layers "F.Paste")
			(roundrect_rratio 0.25)
		)
		(pad "" smd roundrect
			(at 0.299 0.488)
			(size 0.48 0.81)
			(layers "F.Paste")
			(roundrect_rratio 0.25)
		)
		(pad "1" smd roundrect
			(at -1.438 -1.01)
			(size 0.875 0.25)
			(layers "F.Cu" "F.Mask" "F.Paste")
			(roundrect_rratio 0.25)
			(net 9 "Net-(U8-REFIN)")
			(pinfunction "REFIN")
			(pintype "input")
		)
		(pad "2" smd roundrect
			(at -1.438 -0.51)
			(size 0.875 0.25)
			(layers "F.Cu" "F.Mask" "F.Paste")
			(roundrect_rratio 0.25)
			(net 3 "VCC1V35")
			(pinfunction "VLDOIN")
			(pintype "power_in")
		)
		(pad "3" smd roundrect
			(at -1.438 -0.011)
			(size 0.875 0.25)
			(layers "F.Cu" "F.Mask" "F.Paste")
			(roundrect_rratio 0.25)
			(net 143 "/DDR3/DDR3_VTT")
			(pinfunction "VO")
			(pintype "power_out")
		)
		(pad "4" smd roundrect
			(at -1.438 0.488)
			(size 0.875 0.25)
			(layers "F.Cu" "F.Mask" "F.Paste")
			(roundrect_rratio 0.25)
			(net 1 "GND")
			(pinfunction "GND")
			(pintype "passive")
		)
		(pad "5" smd roundrect
			(at -1.438 0.988)
			(size 0.875 0.25)
			(layers "F.Cu" "F.Mask" "F.Paste")
			(roundrect_rratio 0.25)
			(net 143 "/DDR3/DDR3_VTT")
			(pinfunction "VOSNS")
			(pintype "input")
		)
		(pad "6" smd roundrect
			(at 1.437 0.988)
			(size 0.875 0.25)
			(layers "F.Cu" "F.Mask" "F.Paste")
			(roundrect_rratio 0.25)
			(net 211 "DDR3_VREF")
			(pinfunction "REFOUT")
			(pintype "power_out")
		)
		(pad "7" smd roundrect
			(at 1.437 0.488)
			(size 0.875 0.25)
			(layers "F.Cu" "F.Mask" "F.Paste")
			(roundrect_rratio 0.25)
			(net 341 "Net-(U8-EN)")
			(pinfunction "EN")
			(pintype "input")
		)
		(pad "8" smd roundrect
			(at 1.437 -0.011)
			(size 0.875 0.25)
			(layers "F.Cu" "F.Mask" "F.Paste")
			(roundrect_rratio 0.25)
			(net 1 "GND")
			(pinfunction "GND")
			(pintype "power_in")
		)
		(pad "9" smd roundrect
			(at 1.437 -0.51)
			(size 0.875 0.25)
			(layers "F.Cu" "F.Mask" "F.Paste")
			(roundrect_rratio 0.25)
			(net 334 "Net-(U8-PGOOD)")
			(pinfunction "PGOOD")
			(pintype "open_collector")
		)
		(pad "10" smd roundrect
			(at 1.437 -1.01)
			(size 0.875 0.25)
			(layers "F.Cu" "F.Mask" "F.Paste")
			(roundrect_rratio 0.25)
			(net 2 "VCC3V3")
			(pinfunction "VIN")
			(pintype "power_in")
		)
		(pad "11" smd roundrect
			(at 0 -0.011)
			(size 1.2 2)
			(layers "F.Cu" "F.Mask")
			(roundrect_rratio 0.208333)
			(net 1 "GND")
			(pinfunction "GND")
			(pintype "passive")
		)
	)
	(footprint "antmicro-footprints:C_0402_1005Metric"
		(layer "F.Cu")
		(at 91.545 96.575 90)
		(descr "Capacitor SMD 0402")
		(tags "capacitor SMD 0402")
		(property "Reference" "C80"
			(at 0.776 0.355 90)
			(layer "F.SilkS")
			(effects
				(font
					(size 0.7 0.7)
					(thickness 0.15)
				)
				(justify left bottom)
			)
		)
		(property "Value" "C_120p_0402"
			(at 0 1.4 90)
			(layer "F.Fab")
			(effects
				(font
					(size 0.7 0.7)
					(thickness 0.15)
				)
				(justify left bottom)
			)
		)
		(property "Datasheet" "https://www.kemet.com/en/us/capacitors/product/C0402C121J5GACTU.html"
			(at 0 0 90)
			(layer "F.Fab")
			(hide yes)
			(effects
				(font
					(size 1.27 1.27)
					(thickness 0.15)
				)
			)
		)
		(property "Description" "120 pF ±2% 100V Ceramic Capacitor C0G, NP0 0402 (1005 Metric)"
			(at 0 0 90)
			(layer "F.Fab")
			(hide yes)
			(effects
				(font
					(size 1.27 1.27)
					(thickness 0.15)
				)
			)
		)
		(property "Author" "Antmicro"
			(at 188.12 5.03 0)
			(layer "F.Fab")
			(hide yes)
			(effects
				(font
					(size 1 1)
					(thickness 0.15)
				)
			)
		)
		(property "Dielectric" "C0G"
			(at 188.12 5.03 0)
			(layer "F.Fab")
			(hide yes)
			(effects
				(font
					(size 1 1)
					(thickness 0.15)
				)
			)
		)
		(property "License" "Apache-2.0"
			(at 188.12 5.03 0)
			(layer "F.Fab")
			(hide yes)
			(effects
				(font
					(size 1 1)
					(thickness 0.15)
				)
			)
		)
		(property "MPN" "C0402C121J5GACTU"
			(at 188.12 5.03 0)
			(layer "F.Fab")
			(hide yes)
			(effects
				(font
					(size 1 1)
					(thickness 0.15)
				)
			)
		)
		(property "Manufacturer" "KEMET"
			(at 188.12 5.03 0)
			(layer "F.Fab")
			(hide yes)
			(effects
				(font
					(size 1 1)
					(thickness 0.15)
				)
			)
		)
		(property "Val" "120p"
			(at 188.12 5.03 0)
			(layer "F.Fab")
			(hide yes)
			(effects
				(font
					(size 1 1)
					(thickness 0.15)
				)
			)
		)
		(property "Voltage" "100V"
			(at 188.12 5.03 0)
			(layer "F.Fab")
			(hide yes)
			(effects
				(font
					(size 1 1)
					(thickness 0.15)
				)
			)
		)
		(sheetname "/Power supply/")
		(sheetfile "power-supply.kicad_sch")
		(attr smd)
		(fp_rect
			(start -0.925 -0.47)
			(end 0.925 0.47)
			(stroke
				(width 0.05)
				(type default)
			)
			(fill no)
			(layer "F.CrtYd")
		)
		(fp_line
			(start 0.504 -0.25)
			(end 0.504 0.248)
			(stroke
				(width 0.15)
				(type solid)
			)
			(layer "F.Fab")
		)
		(fp_line
			(start -0.494 -0.25)
			(end 0.504 -0.25)
			(stroke
				(width 0.15)
				(type solid)
			)
			(layer "F.Fab")
		)
		(fp_line
			(start 0.504 0.248)
			(end -0.494 0.248)
			(stroke
				(width 0.15)
				(type solid)
			)
			(layer "F.Fab")
		)
		(fp_line
			(start -0.494 0.248)
			(end -0.494 -0.25)
			(stroke
				(width 0.15)
				(type solid)
			)
			(layer "F.Fab")
		)
		(pad "1" smd roundrect
			(at -0.48 0 90)
			(size 0.59 0.64)
			(layers "F.Cu" "F.Mask" "F.Paste")
			(roundrect_rratio 0.25)
			(net 117 "Net-(U11-FB)")
			(pintype "passive")
		)
		(pad "2" smd roundrect
			(at 0.48 0 90)
			(size 0.59 0.64)
			(layers "F.Cu" "F.Mask" "F.Paste")
			(roundrect_rratio 0.25)
			(net 275 "Net-(C80-Pad2)")
			(pintype "passive")
		)
	)
	(footprint "antmicro-footprints:C_0402_1005Metric"
		(layer "F.Cu")
		(at 91.545 103.925 90)
		(descr "Capacitor SMD 0402")
		(tags "capacitor SMD 0402")
		(property "Reference" "C79"
			(at -0.875 3.355 90)
			(layer "F.SilkS")
			(effects
				(font
					(size 0.7 0.7)
					(thickness 0.15)
				)
				(justify left bottom)
			)
		)
		(property "Value" "C_120p_0402"
			(at 0 1.4 90)
			(layer "F.Fab")
			(effects
				(font
					(size 0.7 0.7)
					(thickness 0.15)
				)
				(justify left bottom)
			)
		)
		(property "Datasheet" "https://www.kemet.com/en/us/capacitors/product/C0402C121J5GACTU.html"
			(at 0 0 90)
			(layer "F.Fab")
			(hide yes)
			(effects
				(font
					(size 1.27 1.27)
					(thickness 0.15)
				)
			)
		)
		(property "Description" "120 pF ±2% 100V Ceramic Capacitor C0G, NP0 0402 (1005 Metric)"
			(at 0 0 90)
			(layer "F.Fab")
			(hide yes)
			(effects
				(font
					(size 1.27 1.27)
					(thickness 0.15)
				)
			)
		)
		(property "Author" "Antmicro"
			(at 195.47 12.38 0)
			(layer "F.Fab")
			(hide yes)
			(effects
				(font
					(size 1 1)
					(thickness 0.15)
				)
			)
		)
		(property "Dielectric" "C0G"
			(at 195.47 12.38 0)
			(layer "F.Fab")
			(hide yes)
			(effects
				(font
					(size 1 1)
					(thickness 0.15)
				)
			)
		)
		(property "License" "Apache-2.0"
			(at 195.47 12.38 0)
			(layer "F.Fab")
			(hide yes)
			(effects
				(font
					(size 1 1)
					(thickness 0.15)
				)
			)
		)
		(property "MPN" "C0402C121J5GACTU"
			(at 195.47 12.38 0)
			(layer "F.Fab")
			(hide yes)
			(effects
				(font
					(size 1 1)
					(thickness 0.15)
				)
			)
		)
		(property "Manufacturer" "KEMET"
			(at 195.47 12.38 0)
			(layer "F.Fab")
			(hide yes)
			(effects
				(font
					(size 1 1)
					(thickness 0.15)
				)
			)
		)
		(property "Val" "120p"
			(at 195.47 12.38 0)
			(layer "F.Fab")
			(hide yes)
			(effects
				(font
					(size 1 1)
					(thickness 0.15)
				)
			)
		)
		(property "Voltage" "100V"
			(at 195.47 12.38 0)
			(layer "F.Fab")
			(hide yes)
			(effects
				(font
					(size 1 1)
					(thickness 0.15)
				)
			)
		)
		(sheetname "/Power supply/")
		(sheetfile "power-supply.kicad_sch")
		(attr smd)
		(fp_rect
			(start -0.925 -0.47)
			(end 0.925 0.47)
			(stroke
				(width 0.05)
				(type default)
			)
			(fill no)
			(layer "F.CrtYd")
		)
		(fp_line
			(start 0.504 -0.25)
			(end 0.504 0.248)
			(stroke
				(width 0.15)
				(type solid)
			)
			(layer "F.Fab")
		)
		(fp_line
			(start -0.494 -0.25)
			(end 0.504 -0.25)
			(stroke
				(width 0.15)
				(type solid)
			)
			(layer "F.Fab")
		)
		(fp_line
			(start 0.504 0.248)
			(end -0.494 0.248)
			(stroke
				(width 0.15)
				(type solid)
			)
			(layer "F.Fab")
		)
		(fp_line
			(start -0.494 0.248)
			(end -0.494 -0.25)
			(stroke
				(width 0.15)
				(type solid)
			)
			(layer "F.Fab")
		)
		(pad "1" smd roundrect
			(at -0.48 0 90)
			(size 0.59 0.64)
			(layers "F.Cu" "F.Mask" "F.Paste")
			(roundrect_rratio 0.25)
			(net 113 "Net-(U10-FB)")
			(pintype "passive")
		)
		(pad "2" smd roundrect
			(at 0.48 0 90)
			(size 0.59 0.64)
			(layers "F.Cu" "F.Mask" "F.Paste")
			(roundrect_rratio 0.25)
			(net 274 "Net-(C79-Pad2)")
			(pintype "passive")
		)
	)
	(footprint "antmicro-footprints:C_0603_1608Metric"
		(layer "F.Cu")
		(at 85.175 103.9 -90)
		(descr "Capacitor SMD 0603")
		(tags "capacitor 0603")
		(property "Reference" "C75"
			(at 2 0.575 270)
			(layer "F.SilkS")
			(effects
				(font
					(size 0.7 0.7)
					(thickness 0.15)
				)
				(justify left bottom)
			)
		)
		(property "Value" "C_10u_0603"
			(at 0 1.6 270)
			(layer "F.Fab")
			(effects
				(font
					(size 0.7 0.7)
					(thickness 0.15)
				)
				(justify left bottom)
			)
		)
		(property "Datasheet" "https://www.murata.com/products/productdetail?partno=GRM188R61A106KE69%23"
			(at 0 0 270)
			(layer "F.Fab")
			(hide yes)
			(effects
				(font
					(size 1.27 1.27)
					(thickness 0.15)
				)
			)
		)
		(property "Description" "SMD Multilayer Ceramic Capacitor, 10 µF, 10 V, 0603 [1608 Metric], ± 10%, X5R, GRM Series"
			(at 0 0 270)
			(layer "F.Fab")
			(hide yes)
			(effects
				(font
					(size 1.27 1.27)
					(thickness 0.15)
				)
			)
		)
		(property "Author" "Antmicro"
			(at -18.725 189.075 0)
			(layer "F.Fab")
			(hide yes)
			(effects
				(font
					(size 1 1)
					(thickness 0.15)
				)
			)
		)
		(property "Dielectric" "template_dielectric"
			(at -18.725 189.075 0)
			(layer "F.Fab")
			(hide yes)
			(effects
				(font
					(size 1 1)
					(thickness 0.15)
				)
			)
		)
		(property "License" "Apache-2.0"
			(at -18.725 189.075 0)
			(layer "F.Fab")
			(hide yes)
			(effects
				(font
					(size 1 1)
					(thickness 0.15)
				)
			)
		)
		(property "MPN" "GRM188R61A106KE69D"
			(at -18.725 189.075 0)
			(layer "F.Fab")
			(hide yes)
			(effects
				(font
					(size 1 1)
					(thickness 0.15)
				)
			)
		)
		(property "Manufacturer" "Murata"
			(at -18.725 189.075 0)
			(layer "F.Fab")
			(hide yes)
			(effects
				(font
					(size 1 1)
					(thickness 0.15)
				)
			)
		)
		(property "Val" "10u"
			(at -18.725 189.075 0)
			(layer "F.Fab")
			(hide yes)
			(effects
				(font
					(size 1 1)
					(thickness 0.15)
				)
			)
		)
		(property "Voltage" ""
			(at -18.725 189.075 0)
			(layer "F.Fab")
			(hide yes)
			(effects
				(font
					(size 1 1)
					(thickness 0.15)
				)
			)
		)
		(sheetname "/Power supply/")
		(sheetfile "power-supply.kicad_sch")
		(attr smd)
		(fp_line
			(start -0.15 0.4)
			(end 0.15 0.4)
			(stroke
				(width 0.15)
				(type solid)
			)
			(layer "F.SilkS")
		)
		(fp_line
			(start -0.15 -0.4)
			(end 0.15 -0.4)
			(stroke
				(width 0.15)
				(type solid)
			)
			(layer "F.SilkS")
		)
		(fp_rect
			(start -1.25 -0.65)
			(end 1.25 0.65)
			(stroke
				(width 0.05)
				(type solid)
			)
			(fill no)
			(layer "F.CrtYd")
		)
		(fp_rect
			(start -0.8 -0.4)
			(end 0.8 0.4)
			(stroke
				(width 0.15)
				(type solid)
			)
			(fill no)
			(layer "F.Fab")
		)
		(pad "1" smd roundrect
			(at -0.7 0 270)
			(size 0.8 1)
			(layers "F.Cu" "F.Mask" "F.Paste")
			(roundrect_rratio 0.2)
			(net 1 "GND")
			(pintype "passive")
		)
		(pad "2" smd roundrect
			(at 0.7 0 270)
			(size 0.8 1)
			(layers "F.Cu" "F.Mask" "F.Paste")
			(roundrect_rratio 0.2)
			(net 4 "VCC5V0")
			(pintype "passive")
		)
	)
)
